FILE_TYPE = MULTI_PHYS_TABLE;

PART 'ZENER_AC'

{========================================================================================}
:VALUE             | PART_TYPE | MATERIAL | PART_NUMBER    = STANDARD        | LIFECYCLE     | PART_NUMBER   | JEDEC_TYPE           | DESCRIPTION                                | MANUFTR | MANUF_PN          | RD_CMPLS_LVL | CMPLS_LVL | CLASS | DIP_SMD | FP_ECN | FROM_PJ       | DATA                             | EE_CHECK_LIST | STATUS | PSL | PREFERENCE | CREATOR | CREATEDAY  ;
{========================================================================================}
 'BZX585-C18/DG'   | 'SMLF'    | 'IC'     | 'BC000C18Z00'(!) = ''              | ''            | 'BC000C18Z00' |'SOD523'| 'DIODE BZX585-C18/DG(75V 200MA SOD523)'    | 'NXP'   | 'BZX585-C18/DG'   | 'EP(V1)'     | ''        | 'IC'  | ''      | ''     | 'S99Q-WIM'    | 'BZX585.pdf'                     | ''            | ''     | ''  | ''         | ''      | '20100429'
 'BZX585-C18/DG'   | 'SMLF'    | 'EMPTY'  | 'BC000C18Z00'(!) = ''              | ''            | 'BC000C18Z00' |'SOD523'| 'DIODE BZX585-C18/DG(75V 200MA SOD523)'    | 'NXP'   | 'BZX585-C18/DG'   | 'EP(V1)'     | ''        | 'IC'  | ''      | ''     | 'S99Q-WIM'    | 'BZX585.pdf'                     | ''            | ''     | ''  | ''         | ''      | '20100429'
 'SMB10J14A'       | 'SMLF'    | 'IC'     | 'BC10J14AZ00'(!) = ''              | ''            | 'BC10J14AZ00' |'D2114'| 'DIODE SMB SMB10J14AHE3/52(14V.1MA.TVS)'   | 'SIL'   | 'SMB10J14AHE3/52' | ''           | 'EP_Tmp'  | 'IC'  | ''      | ''     | 'T96-JAMES'   | 'SIL_SMB10.pdf'                  | ''            | ''     | ''  | ''         | ''      | '20100429'
 'SMB10J14A'       | 'SMLF'    | 'EMPTY'  | 'BC10J14AZ00'(!) = ''              | ''            | 'BC10J14AZ00' |'D2114'| 'DIODE SMB SMB10J14AHE3/52(14V.1MA.TVS)'   | 'SIL'   | 'SMB10J14AHE3/52' | ''           | 'EP_Tmp'  | 'IC'  | ''      | ''     | 'T96-JAMES'   | 'SIL_SMB10.pdf'                  | ''            | ''     | ''  | ''         | ''      | '20100429'
 'SMAJ12A-13-F'    | 'SMLF'    | 'IC'     | 'BCMAJ12AZ00'(!) = ''              | ''            | 'BCMAJ12AZ00' |'D2114'| 'DIODE SMD SMAJ12A-13-F(12V.20.1A.400W)'   | 'DDS'   | 'SMAJ12A-13-F'    | ''           | 'EP_Tmp'  | 'IC'  | ''      | ''     | 'LU1-ROGER'   | 'DDS_SMAJ5(C)A-SMAJ170(C)A.pdf'  | ''            | ''     | ''  | ''         | ''      | '20100429'
 'SMAJ12A-13-F'    | 'SMLF'    | 'EMPTY'  | 'BCMAJ12AZ00'(!) = ''              | ''            | 'BCMAJ12AZ00' |'D2114'| 'DIODE SMD SMAJ12A-13-F(12V.20.1A.400W)'   | 'DDS'   | 'SMAJ12A-13-F'    | ''           | 'EP_Tmp'  | 'IC'  | ''      | ''     | 'LU1-ROGER'   | 'DDS_SMAJ5(C)A-SMAJ170(C)A.pdf'  | ''            | ''     | ''  | ''         | ''      | '20100429'
 'SMAJ13A-13-F'    | 'SMLF'    | 'IC'     | 'BCMAJ13AZ00'(!) = ''              | ''            | 'BCMAJ13AZ00' |'D2010XF'| 'DIODE SMD SMAJ13A-13-F(13V,18.6A,400W)'   | 'DDS'   | 'SMAJ13A-13-F'    | 'EU(V1)'     | 'EU(V1)'  | 'IC'  | ''      | ''     | 'S1M-MARK'    | 'DDS_SMAJ5-0C-A_SMAJ200-C-A.pdf' | ''            | ''     | ''  | ''         | ''      | '20130118'
 'SMAJ13A-13-F'    | 'SMLF'    | 'EMPTY'  | 'BCMAJ13AZ00'(!) = ''              | ''            | 'BCMAJ13AZ00' |'D2010XF'| 'DIODE SMD SMAJ13A-13-F(13V,18.6A,400W)'   | 'DDS'   | 'SMAJ13A-13-F'    | 'EU(V1)'     | 'EU(V1)'  | 'IC'  | ''      | ''     | 'S1M-MARK'    | 'DDS_SMAJ5-0C-A_SMAJ200-C-A.pdf' | ''            | ''     | ''  | ''         | ''      | '20130118'
 'SMAJ18A-13-F'    | 'SMLF'    | 'IC'     | 'BCMAJ18AZ00'(!) = ''              | ''            | 'BCMAJ18AZ00' |'D2010XF'| 'DIODE SMD SMAJ18A-13-F(18V,13.7A,400W)'   | 'DDS'   | 'SMAJ18A-13-F'    | 'EP(V1)'     | ''        | 'IC'  | ''      | ''     | 'S1M-MARK'    | 'DDS_SMAJ5-0C-A_SMAJ200-C-A.pdf' | ''            | ''     | ''  | ''         | ''      | '20121218'
 'SMAJ18A-13-F'    | 'SMLF'    | 'EMPTY'  | 'BCMAJ18AZ00'(!) = ''              | ''            | 'BCMAJ18AZ00' |'D2010XF'| 'DIODE SMD SMAJ18A-13-F(18V,13.7A,400W)'   | 'DDS'   | 'SMAJ18A-13-F'    | 'EP(V1)'     | ''        | 'IC'  | ''      | ''     | 'S1M-MARK'    | 'DDS_SMAJ5-0C-A_SMAJ200-C-A.pdf' | ''            | ''     | ''  | ''         | ''      | '20121218'
 'T3V3S5-7'        | 'SMLF'    | 'IC'     | 'BCT3V3S5Z00'(!) = ''              | ''            | 'BCT3V3S5Z00' |'SOD523XA'| 'DIODE SMD T3V3S5-7(0.9V,10MA)SOD523'      | 'DDS'   | 'T3V3S5-7'        | 'EP(V1)'     | ''        | 'IC'  | ''      | ''     | 'L10-WIN'     | 'DDS_T3V3S5_REV10-2.pdf'         | ''            | ''     | ''  | ''         | ''      | '20140515'
 'T3V3S5-7'        | 'SMLF'    | 'EMPTY'  | 'BCT3V3S5Z00'(!) = ''              | ''            | 'BCT3V3S5Z00' |'SOD523XA'| 'DIODE SMD T3V3S5-7(0.9V,10MA)SOD523'      | 'DDS'   | 'T3V3S5-7'        | 'EP(V1)'     | ''        | 'IC'  | ''      | ''     | 'L10-WIN'     | 'DDS_T3V3S5_REV10-2.pdf'         | ''            | ''     | ''  | ''         | ''      | '20140515'
 'MMSZ5245B'       | 'SMLF'    | 'IC'     | 'BD005245Z00'(!) = ''              | ''            | 'BD005245Z00' |'SOD123XD'| 'DIOIDE ZENER SMD MMSZ5245B(15V,SOD123)'   | 'PJT'   | 'MMSZ5245B'       | 'EP(V1)'     | 'EP(V1)'  | 'IC'  | ''      | ''     | 'JS9-JACK'    | 'PJT_MMSZ5245B-SERIES.pdf'       | ''            | ''     | ''  | ''         | ''      | '20130131'
 'MMSZ5245B'       | 'SMLF'    | 'EMPTY'  | 'BD005245Z00'(!) = ''              | ''            | 'BD005245Z00' |'SOD123XD'| 'DIOIDE ZENER SMD MMSZ5245B(15V,SOD123)'   | 'PJT'   | 'MMSZ5245B'       | 'EP(V1)'     | 'EP(V1)'  | 'IC'  | ''      | ''     | 'JS9-JACK'    | 'PJT_MMSZ5245B-SERIES.pdf'       | ''            | ''     | ''  | ''         | ''      | '20130131'
 'BZT52-B18S'      | 'SMLF'    | 'IC'     | 'BD52B18SZ00'(!) = ''              | ''            | 'BD52B18SZ00' |'SOD323XD'| 'DIODE ZENER SMD BZT52-B18S(17.64V-18.36)' | 'PJT'   | 'BZT52-B18S'      | 'EP(V1)'     | 'EP(V1)'  | 'IC'  | ''      | ''     | 'S1VL-TIM'    | 'PJT_BZT52-B2V4S SERIES.pdf'     | ''            | ''     | ''  | ''         | ''      | '20130820'
 'BZT52-B18S'      | 'SMLF'    | 'EMPTY'  | 'BD52B18SZ00'(!) = ''              | ''            | 'BD52B18SZ00' |'SOD323XD'| 'DIODE ZENER SMD BZT52-B18S(17.64V-18.36)' | 'PJT'   | 'BZT52-B18S'      | 'EP(V1)'     | 'EP(V1)'  | 'IC'  | ''      | ''     | 'S1VL-TIM'    | 'PJT_BZT52-B2V4S SERIES.pdf'     | ''            | ''     | ''  | ''         | ''      | '20130820'
 'BZT52-B5V1S'     | 'SMLF'    | 'IC'     | 'BD52B5V1Z00'(!) = ''              | ''            | 'BD52B5V1Z00' |'SOD323XD'| 'DIODE ZENER SMD BZT52-B5V1S(5.00V-5.20V)' | 'PJT'   | 'BZT52-B5V1S'     | 'EP(V1)'     | 'EP(V1)'  | 'IC'  | ''      | ''     | 'JS9-JACK'    | 'PJT_BZT52-B2V4S SERIES.pdf'     | ''            | ''     | ''  | ''         | ''      | '20130128'
 'BZT52-B5V1S'     | 'SMLF'    | 'EMPTY'  | 'BD52B5V1Z00'(!) = ''              | ''            | 'BD52B5V1Z00' |'SOD323XD'| 'DIODE ZENER SMD BZT52-B5V1S(5.00V-5.20V)' | 'PJT'   | 'BZT52-B5V1S'     | 'EP(V1)'     | 'EP(V1)'  | 'IC'  | ''      | ''     | 'JS9-JACK'    | 'PJT_BZT52-B2V4S SERIES.pdf'     | ''            | ''     | ''  | ''         | ''      | '20130128'
 'BZT52-B6V8S'     | 'SMLF'    | 'IC'     | 'BD52B6V8Z00'(!) = ''              | ''            | 'BD52B6V8Z00' |'SOD323XD'| 'DIODE ZENER SMD BZT52-B6V8S(6.66V-6.94V)' | 'PJT'   | 'BZT52-B6V8S'     | 'EP(V1)'     | ''        | 'IC'  | ''      | ''     | 'JS9-JACK'    | 'PJT_BZT52-B2V4S-SERIES.pdf'     | ''            | ''     | ''  | ''         | ''      | '20130128'
 'BZT52-B6V8S'     | 'SMLF'    | 'EMPTY'  | 'BD52B6V8Z00'(!) = ''              | ''            | 'BD52B6V8Z00' |'SOD323XD'| 'DIODE ZENER SMD BZT52-B6V8S(6.66V-6.94V)' | 'PJT'   | 'BZT52-B6V8S'     | 'EP(V1)'     | ''        | 'IC'  | ''      | ''     | 'JS9-JACK'    | 'PJT_BZT52-B2V4S-SERIES.pdf'     | ''            | ''     | ''  | ''         | ''      | '20130128'
 'BZT52C3V6S-7-F'  | 'SMLF'    | 'IC'     | 'BD52C3V6Z02'(!) = ''              | ''            | 'BD52C3V6Z02' |'SOD323XI'| 'DIODE ZENER SMD BZT52C3V6S-7-F 3.4V~3.8V' | 'DDS'   | 'BZT52C3V6S-7-F'  | 'EP(V1)'     | 'EP(V1)'  | 'IC'  | ''      | ''     | 'T2R-MARK'    | 'DDS_BZT52CXX_REV16-2.pdf'       | ''            | ''     | ''  | ''         | ''      | '20140304'
 'BZT52C3V6S-7-F'  | 'SMLF'    | 'EMPTY'  | 'BD52C3V6Z02'(!) = ''              | ''            | 'BD52C3V6Z02' |'SOD323XI'| 'DIODE ZENER SMD BZT52C3V6S-7-F 3.4V~3.8V' | 'DDS'   | 'BZT52C3V6S-7-F'  | 'EP(V1)'     | 'EP(V1)'  | 'IC'  | ''      | ''     | 'T2R-MARK'    | 'DDS_BZT52CXX_REV16-2.pdf'       | ''            | ''     | ''  | ''         | ''      | '20140304'
 'BZT52C5V6S-7-F'  | 'SMLF'    | 'IC'     | 'BD52C5V6Z03'(!) = ''              | ''            | 'BD52C5V6Z03' |'SOD323XI'| 'DIODE ZENER BZT52C5V6S-7-F(5.6V)SOD323'   | 'DDS'   | 'BZT52C5V6S-7-F'  | 'EP(V1)'     | 'EP(V1)'  | 'IC'  | ''      | ''     | 'T2R-MARK'    | 'DDS_BZT52CXX_REV16-2.pdf'       | ''            | ''     | ''  | ''         | ''      | '20140226'
 'BZT52C5V6S-7-F'  | 'SMLF'    | 'EMPTY'  | 'BD52C5V6Z03'(!) = ''              | ''            | 'BD52C5V6Z03' |'SOD323XI'| 'DIODE ZENER BZT52C5V6S-7-F(5.6V)SOD323'   | 'DDS'   | 'BZT52C5V6S-7-F'  | 'EP(V1)'     | 'EP(V1)'  | 'IC'  | ''      | ''     | 'T2R-MARK'    | 'DDS_BZT52CXX_REV16-2.pdf'       | ''            | ''     | ''  | ''         | ''      | '20140226'
 'TVSS5VESPT'      | 'SMLF'    | 'IC'     | 'BD5VESPTZ00'(!) = 'End of Design' | 'End of Life' | 'BD5VESPTZ00' |'SOD523_EOL'| 'DIODE ZENER SMD TVSS5VESPT(18.6V.9.4A)'   | 'CNK'   | 'TVSS5VESPT'      | ''           | 'EP(V1)'  | 'IC'  | ''      | ''     | 'S99Q-WIM'    | 'CNK_TVSS5VESPT.pdf'             | ''            | ''     | ''  | ''         | ''      | '20100429'
 'TVSS5VESPT'      | 'SMLF'    | 'EMPTY'  | 'BD5VESPTZ00'(!) = 'End of Design' | 'End of Life' | 'BD5VESPTZ00' |'SOD523_EOL'| 'DIODE ZENER SMD TVSS5VESPT(18.6V.9.4A)'   | 'CNK'   | 'TVSS5VESPT'      | ''           | 'EP(V1)'  | 'IC'  | ''      | ''     | 'S99Q-WIM'    | 'CNK_TVSS5VESPT.pdf'             | ''            | ''     | ''  | ''         | ''      | '20100429'
 'SMBT70A'         | 'SMLF'    | 'IC'     | 'BDMBT70AZ00'(!) = ''              | ''            | 'BDMBT70AZ00' |'D2114A'| 'DIODE ZENER SMD SMBT70A-13-F 100V TVS'    | 'DDS'   | 'SMBT70A-13-F'    | ''           | 'EP_Tmp'  | 'IC'  | ''      | ''     | 'S80-WALLACE' | 'SMAT70A-SMBT70A.pdf'            | ''            | ''     | ''  | ''         | ''      | '20100429'
 'SMBT70A'         | 'SMLF'    | 'EMPTY'  | 'BDMBT70AZ00'(!) = ''              | ''            | 'BDMBT70AZ00' |'D2114A'| 'DIODE ZENER SMD SMBT70A-13-F 100V TVS'    | 'DDS'   | 'SMBT70A-13-F'    | ''           | 'EP_Tmp'  | 'IC'  | ''      | ''     | 'S80-WALLACE' | 'SMAT70A-SMBT70A.pdf'            | ''            | ''     | ''  | ''         | ''      | '20100429'
 'SMAZ15-13-F'     | 'SMLF'    | 'IC'     | 'BDSMAZ15Z00'(!) = ''              | ''            | 'BDSMAZ15Z00' |'D2010XF'| 'DIODE ZENER SMD SMAZ15-13-F(14.25~15.7V)' | 'DDS'   | 'SMAZ15-13-F'     | 'EP(V1)'     | ''        | 'IC'  | ''      | ''     | 'JB5-CHINWEI' | 'SMAZ5V1-SMAZ39.pdf'             | ''            | ''     | ''  | ''         | ''      | '20100429'
 'SMAZ15-13-F'     | 'SMLF'    | 'EMPTY'  | 'BDSMAZ15Z00'(!) = ''              | ''            | 'BDSMAZ15Z00' |'D2010XF'| 'DIODE ZENER SMD SMAZ15-13-F(14.25~15.7V)' | 'DDS'   | 'SMAZ15-13-F'     | 'EP(V1)'     | ''        | 'IC'  | ''      | ''     | 'JB5-CHINWEI' | 'SMAZ5V1-SMAZ39.pdf'             | ''            | ''     | ''  | ''         | ''      | '20100429'
 'SMAZ6V8-13-F'    | 'SMLF'    | 'IC'     | 'BDSMAZ6VZ00'(!) = ''              | ''            | 'BDSMAZ6VZ00' |'D2010XF'| 'DIODE ZENER SMD SMAZ6V8-13-F(6.46~7.14V)' | 'DDS'   | 'SMAZ6V8-13-F'    | 'EP(V1)'     | ''        | 'IC'  | ''      | ''     | 'JB5-CHINWEI' | 'SMAZ5V1-SMAZ39.pdf'             | ''            | ''     | ''  | ''         | ''      | '20100429'
 'SMAZ6V8-13-F'    | 'SMLF'    | 'EMPTY'  | 'BDSMAZ6VZ00'(!) = ''              | ''            | 'BDSMAZ6VZ00' |'D2010XF'| 'DIODE ZENER SMD SMAZ6V8-13-F(6.46~7.14V)' | 'DDS'   | 'SMAZ6V8-13-F'    | 'EP(V1)'     | ''        | 'IC'  | ''      | ''     | 'JB5-CHINWEI' | 'SMAZ5V1-SMAZ39.pdf'             | ''            | ''     | ''  | ''         | ''      | '20100429'
 '5.0SMDJ13A'      | 'SMLF'    | 'IC'     | 'BC0MDJ13Z00'(!) = ''              | ''            | 'BC0MDJ13Z00' |'D2723_SMCXC'| 'DIODE SMD 5.0SMDJ13A(13V,233A)DO-214AB'   | 'LFI'   | '5.0SMDJ13A'      | 'EP(V1)'     | ''        | 'IC'  | ''      | ''     | 'UQ3-TOM'     | '5-0SMD SERIES.pdf'              | ''            | ''     | ''  | ''         | ''      | '20140902'
 '5.0SMDJ13A'      | 'SMLF'    | 'EMPTY'  | 'BC0MDJ13Z00'(!) = ''              | ''            | 'BC0MDJ13Z00' |'D2723_SMCXC'| 'DIODE SMD 5.0SMDJ13A(13V,233A)DO-214AB'   | 'LFI'   | '5.0SMDJ13A'      | 'EP(V1)'     | ''        | 'IC'  | ''      | ''     | 'UQ3-TOM'     | '5-0SMD SERIES.pdf'              | ''            | ''     | ''  | ''         | ''      | '20140902'
 'MMSZ5229B'       | 'SMLF'    | 'IC'     | 'BD05229BZ00'(!) = ''              | ''            | 'BD05229BZ00' |'SOD123_2-7X1-6'| 'DIODE ZENER MMSZ5229B(4.3V, 0.5W)'        | 'FAC'   | 'MMSZ5229B'       | 'EP(V1)'     | ''        | 'IC'  | ''      | ''     | 'T6MG-MRAK'   | 'FAC_MMSZ5229B_REV1.1.1.pdf'     | ''            | ''     | ''  | ''         | ''      | '20141223'
 'MMSZ5229B'       | 'SMLF'    | 'EMPTY'  | 'BD05229BZ00'(!) = ''              | ''            | 'BD05229BZ00' |'SOD123_2-7X1-6'| 'DIODE ZENER MMSZ5229B(4.3V, 0.5W)'        | 'FAC'   | 'MMSZ5229B'       | 'EP(V1)'     | ''        | 'IC'  | ''      | ''     | 'T6MG-MRAK'   | 'FAC_MMSZ5229B_REV1.1.1.pdf'     | ''            | ''     | ''  | ''         | ''      | '20141223'
 '5.0SMDJ16A'      | 'SMLF'    | 'IC'     | 'BC0MDJ16Z00'(!) = ''              | ''            | 'BC0MDJ16Z00' |'D2723_SMCXC'| 'DIODE SMD 5.0SMDJ16A(16V,193A,6.5W)'      | 'LFI'   | '5.0SMDJ16A'      | 'EP(V1)'     | ''        | 'IC'  | ''      | ''     | 'T2HV-JOHN'   | 'LFI_5.0SMDJ16A.pdf'             | ''            | ''     | ''  | ''         | ''      | '20151214'
 '5.0SMDJ16A'      | 'SMLF'    | 'EMPTY'  | 'BC0MDJ16Z00'(!) = ''              | ''            | 'BC0MDJ16Z00' |'D2723_SMCXC'| 'DIODE SMD 5.0SMDJ16A(16V,193A,6.5W)'      | 'LFI'   | '5.0SMDJ16A'      | 'EP(V1)'     | ''        | 'IC'  | ''      | ''     | 'T2HV-JOHN'   | 'LFI_5.0SMDJ16A.pdf'             | ''            | ''     | ''  | ''         | ''      | '20151214'
 '5.0SMDJ14A'      | 'SMLF'    | 'IC'     | 'BC0MDJ14000'(!) = ''              | ''            | 'BC0MDJ14000' |'D2723_SMCXC'| 'DIODE SMD 5.0SMDJ14A(14V,216A,5000W)'     | 'LFI'   | '5.0SMDJ14A'      | 'EP(V1)'     | ''        | 'IC'  | ''      | ''     | 'T2HV-JOHN'   | 'LFI_5.0SMDJ14A.pdf'             | ''            | ''     | ''  | ''         | ''      | '20151225'
 '5.0SMDJ14A'      | 'SMLF'    | 'EMPTY'  | 'BC0MDJ14000'(!) = ''              | ''            | 'BC0MDJ14000' |'D2723_SMCXC'| 'DIODE SMD 5.0SMDJ14A(14V,216A,5000W)'     | 'LFI'   | '5.0SMDJ14A'      | 'EP(V1)'     | ''        | 'IC'  | ''      | ''     | 'T2HV-JOHN'   | 'LFI_5.0SMDJ14A.pdf'             | ''            | ''     | ''  | ''         | ''      | '20151225'
 '5.0SMDJ15A'      | 'SMLF'    | 'IC'     | 'BC00015AZ00'(!) = ''              | ''            | 'BC00015AZ00' |'D2723_SMCXC'| 'DIODE SMD 5.0SMDJ15A(15V,205A,5000W)'     | 'LFI'   | '5.0SMDJ15A'      | 'EP(V1)'     | ''        | 'IC'  | ''      | ''     | 'T2HV-MARK'   | 'LFI_5.0SMDJ15A.pdf'             | ''            | ''     | ''  | ''         | ''      | '20160120'
 '5.0SMDJ15A'      | 'SMLF'    | 'EMPTY'  | 'BC00015AZ00'(!) = ''              | ''            | 'BC00015AZ00' |'D2723_SMCXC'| 'DIODE SMD 5.0SMDJ15A(15V,205A,5000W)'     | 'LFI'   | '5.0SMDJ15A'      | 'EP(V1)'     | ''        | 'IC'  | ''      | ''     | 'T2HV-MARK'   | 'LFI_5.0SMDJ15A.pdf'             | ''            | ''     | ''  | ''         | ''      | '20160120'
 'BZT52C3V6SQ-7-F' | 'SMLF'    | 'IC'     | 'BD52C3V6000'(!) = ''              | ''            | 'BD52C3V6000' |'SOD323XI'| 'DIODE ZENER BZT52C3V6SQ-7-F(3.6V,5MA)AEC' | 'DDS'   | 'BZT52C3V6SQ-7-F' | 'EP(V1)'     | ''        | 'IC'  | ''      | ''     | 'T2HV-MARK'   | 'DDS _BZT52C3V6SQ-7-F.pdf'       | ''            | ''     | ''  | ''         | ''      | '20160324'
 'BZT52C3V6SQ-7-F' | 'SMLF'    | 'EMPTY'  | 'BD52C3V6000'(!) = ''              | ''            | 'BD52C3V6000' |'SOD323XI'| 'DIODE ZENER BZT52C3V6SQ-7-F(3.6V,5MA)AEC' | 'DDS'   | 'BZT52C3V6SQ-7-F' | 'EP(V1)'     | ''        | 'IC'  | ''      | ''     | 'T2HV-MARK'   | 'DDS _BZT52C3V6SQ-7-F.pdf'       | ''            | ''     | ''  | ''         | ''      | '20160324'
 'BZT52C3V3LP-7'   | 'SMLF'    | 'IC'     | 'BDC3V3LPZ00'(!) = ''              | ''            | 'BDC3V3LPZ00' |'D0402XA'| 'DIODE ZENER BZT52C3V3LP-7(3.3V,5MA)'      | 'DDS'   | 'BZT52C3V3LP-7'   | 'EP(V1)'     | 'EP(V1)'  | 'IC'  | ''      | ''     | 'JBW-TONY'    | 'DDS_BZT52C3V3LP-7.pdf'          | ''            | ''     | ''  | ''         | ''      | '20170508'
 'BZT52C3V3LP-7'   | 'SMLF'    | 'EMPTY'  | 'BDC3V3LPZ00'(!) = ''              | ''            | 'BDC3V3LPZ00' |'D0402XA'| 'DIODE ZENER BZT52C3V3LP-7(3.3V,5MA)'      | 'DDS'   | 'BZT52C3V3LP-7'   | 'EP(V1)'     | 'EP(V1)'  | 'IC'  | ''      | ''     | 'JBW-TONY'    | 'DDS_BZT52C3V3LP-7.pdf'          | ''            | ''     | ''  | ''         | ''      | '20170508'
 'BZX584C5V6'      | 'SMLF'    | 'IC'     | 'BD584C5VZ00'(!) = ''              | ''            | 'BD584C5VZ00' |'SOD523_1-2X0-8XB'| 'DIODE ZENER BZX584C5V6(5.6V,5MA)SOD-523)' | 'PJT'   | 'BZX584C5V6'      | 'EP'         | 'EP'      | 'IC'  | ''      | ''     | 'F09-SEAN'    | 'PJT_BZX584C5V6.pdf'             | ''            | ''     | ''  | ''         | ''      | '20170929'
 'BZX584C5V6'      | 'SMLF'    | 'EMPTY'  | 'BD584C5VZ00'(!) = ''              | ''            | 'BD584C5VZ00' |'SOD523_1-2X0-8XB'| 'DIODE ZENER BZX584C5V6(5.6V,5MA)SOD-523)' | 'PJT'   | 'BZX584C5V6'      | 'EP'         | 'EP'      | 'IC'  | ''      | ''     | 'F09-SEAN'    | 'PJT_BZX584C5V6.pdf'             | ''            | ''     | ''  | ''         | ''      | '20170929'
 '1SMC13AT3G'      | 'SMLF'    | 'IC'     | 'BD1SMC13Z00'(!) = ''              | ''            | 'BD1SMC13Z00' |'D2723_SMCXJ'| 'DIODE ZENER SMD 1SMC13AT3G(13V,0.75W)'    | 'ONS'   | '1SMC13AT3G'      | 'EP(V1)'     | ''        | 'IC'  | ''      | ''     | 'F09-SEAN'    | 'ONS_1SMC13AT3G.pdf'             | ''            | ''     | ''  | ''         | ''      | '20171020'
 '1SMC13AT3G'      | 'SMLF'    | 'EMPTY'  | 'BD1SMC13Z00'(!) = ''              | ''            | 'BD1SMC13Z00' |'D2723_SMCXJ'| 'DIODE ZENER SMD 1SMC13AT3G(13V,0.75W)'    | 'ONS'   | '1SMC13AT3G'      | 'EP(V1)'     | ''        | 'IC'  | ''      | ''     | 'F09-SEAN'    | 'ONS_1SMC13AT3G.pdf'             | ''            | ''     | ''  | ''         | ''      | '20171020'
 'MMSZ5229BT1G'    | 'SMLF'    | 'IC'     | 'BD005229Z00'(!) = ''              | ''            | 'BD005229Z00' |'SOD123XE'| 'DIODE ZENER MMSZ5229BT1G(4.3V,0.5W)'      | 'ONS'   | 'MMSZ5229BT1G'    | 'EP(V1)'     | ''        | 'IC'  | ''      | ''     | 'S6V-JW'      | 'ONS_MMSZ5229BT1G.pdf'           | ''            | ''     | ''  | ''         | ''      | '20180910'
 'MMSZ5229BT1G'    | 'SMLF'    | 'EMPTY'  | 'BD005229Z00'(!) = ''              | ''            | 'BD005229Z00' |'SOD123XE'| 'DIODE ZENER MMSZ5229BT1G(4.3V,0.5W)'      | 'ONS'   | 'MMSZ5229BT1G'    | 'EP(V1)'     | ''        | 'IC'  | ''      | ''     | 'S6V-JW'      | 'ONS_MMSZ5229BT1G.pdf'           | ''            | ''     | ''  | ''         | ''      | '20180910'
 'PDZ3.3B'         | 'SMLF'    | 'IC'     | 'BDPDZ33BZ01'(!) = ''              | ''            | 'BDPDZ33BZ01' |'SOD323F_H44'| 'DIODE ZENER SMD PDZ3.3B(3.32V-3.53V)'     | 'PHI'   | 'PDZ3.3B'         | 'EP(V1)'     | 'EP(V1)'  | 'IC'  | ''      | ''     | 'JG5-TOM'     | 'PHI_PDZ3.3B.pdf'                | ''            | ''     | ''  | ''         | ''      | '20181105'
 'PDZ3.3B'         | 'SMLF'    | 'EMPTY'  | 'BDPDZ33BZ01'(!) = ''              | ''            | 'BDPDZ33BZ01' |'SOD323F_H44'| 'DIODE ZENER SMD PDZ3.3B(3.32V-3.53V)'     | 'PHI'   | 'PDZ3.3B'         | 'EP(V1)'     | 'EP(V1)'  | 'IC'  | ''      | ''     | 'JG5-TOM'     | 'PHI_PDZ3.3B.pdf'                | ''            | ''     | ''  | ''         | ''      | '20181105'
 'BZX884-C4V7'     | 'SMLF'    | 'IC'     | 'BD84C4V7Z00'(!) = ''              | ''            | 'BD84C4V7Z00' |'SOD882_0-985X0-585'| 'DIODE ZENER BZX884(4.47-4.95V,0.2A,0.25W' | 'NXE'   | 'BZX884-C4V7'     | 'EP(V1)'     | 'EP(V1)'  | 'IC'  | ''      | ''     | 'S5U-JOANNE'  | 'NXE_BZX884-C4V7.pdf'            | ''            | ''     | ''  | ''         | ''      | '20190119'
 'BZX884-C4V7'     | 'SMLF'    | 'EMPTY'  | 'BD84C4V7Z00'(!) = ''              | ''            | 'BD84C4V7Z00' |'SOD882_0-985X0-585'| 'DIODE ZENER BZX884(4.47-4.95V,0.2A,0.25W' | 'NXE'   | 'BZX884-C4V7'     | 'EP(V1)'     | 'EP(V1)'  | 'IC'  | ''      | ''     | 'S5U-JOANNE'  | 'NXE_BZX884-C4V7.pdf'            | ''            | ''     | ''  | ''         | ''      | '20190119'
 'BZX384-C12'      | 'SMLF'    | 'IC'     | 'BC384C12Z00'(!) = ''              | ''            | 'BC384C12Z00' |'SOD323F_H44'| 'DIODE SMD BZX384-C12(0.9V,0.25A,0.3W)'    | 'NXE'   | 'BZX384-C12'      | 'EP(V1)'     | ''        | 'IC'  | ''      | ''     | 'BAICELL-MJ'  | 'NXE_BZX384-C12.pdf'             | ''            | ''     | ''  | ''         | ''      | '20190129'
 'BZX384-C12'      | 'SMLF'    | 'EMPTY'  | 'BC384C12Z00'(!) = ''              | ''            | 'BC384C12Z00' |'SOD323F_H44'| 'DIODE SMD BZX384-C12(0.9V,0.25A,0.3W)'    | 'NXE'   | 'BZX384-C12'      | 'EP(V1)'     | ''        | 'IC'  | ''      | ''     | 'BAICELL-MJ'  | 'NXE_BZX384-C12.pdf'             | ''            | ''     | ''  | ''         | ''      | '20190129'
 'MMSZ3V9T1G'      | 'SMLF'    | 'IC'     | 'BD03V9T1000'(!) = ''              | ''            | 'BD03V9T1000' |'SOD123XE'| 'DIODE ZENER MMSZ3V9T1G(3.9V,0.5W)'        | 'ONS'   | 'MMSZ3V9T1G'      | 'EP(V1)'     | ''        | 'IC'  | ''      | ''     | 'F09-JANE'    | 'ONS_MMSZ3V9T1G.pdf'             | ''            | ''     | ''  | ''         | ''      | '20180308'
 'MMSZ3V9T1G'      | 'SMLF'    | 'EMPTY'  | 'BD03V9T1000'(!) = ''              | ''            | 'BD03V9T1000' |'SOD123XE'| 'DIODE ZENER MMSZ3V9T1G(3.9V,0.5W)'        | 'ONS'   | 'MMSZ3V9T1G'      | 'EP(V1)'     | ''        | 'IC'  | ''      | ''     | 'F09-JANE'    | 'ONS_MMSZ3V9T1G.pdf'             | ''            | ''     | ''  | ''         | ''      | '20180308'
 'MMSZ5230B-7-F'   | 'SMLF'    | 'IC'     | 'BD005230Z01'(!) = ''              | ''            | 'BD005230Z01' |'SOD123_2-7X1-55XA'| 'DIODE ZENER SMD MMSZ5230B(4.7V,SOD123)'   | 'DDS'   | 'MMSZ5230B-7-F'   | 'EP(V1)'     | 'EP(V1)'  | 'IC'  | ''      | ''     | 'S8I-LEO'     | 'DDS_MMSZ5230B-7-F.pdf'          | ''            | ''     | ''  | ''         | ''      | '20190925'
 'MMSZ5230B-7-F'   | 'SMLF'    | 'EMPTY'  | 'BD005230Z01'(!) = ''              | ''            | 'BD005230Z01' |'SOD123_2-7X1-55XA'| 'DIODE ZENER SMD MMSZ5230B(4.7V,SOD123)'   | 'DDS'   | 'MMSZ5230B-7-F'   | 'EP(V1)'     | 'EP(V1)'  | 'IC'  | ''      | ''     | 'S8I-LEO'     | 'DDS_MMSZ5230B-7-F.pdf'          | ''            | ''     | ''  | ''         | ''      | '20190925'
 'BZT52-B12S'      | 'SMLF'    | 'IC'     | 'BD52B12SZ00'(!) = ''              | ''            | 'BD52B12SZ00' |'SOD323_1-85X1-25'| 'DIODE ZENER SMD BZT52-B12S(11.76-12.24V)' | 'PJT'   | 'BZT52-B12S'      | 'EP(V1)'     | 'EP(V1)'  | 'IC'  | ''      | ''     | 'S8A-JAY'     | 'PJT_BZT52-B12S.pdf'             | ''            | ''     | ''  | ''         | ''      | '20200324'
 'BZT52-B12S'      | 'SMLF'    | 'EMPTY'  | 'BD52B12SZ00'(!) = ''              | ''            | 'BD52B12SZ00' |'SOD323_1-85X1-25'| 'DIODE ZENER SMD BZT52-B12S(11.76-12.24V)' | 'PJT'   | 'BZT52-B12S'      | 'EP(V1)'     | 'EP(V1)'  | 'IC'  | ''      | ''     | 'S8A-JAY'     | 'PJT_BZT52-B12S.pdf'             | ''            | ''     | ''  | ''         | ''      | '20200324'
 'BZT52-B3V6S'     | 'SMLF'    | 'IC'     | 'BD2B3V6SZ00'(!) = ''              | ''            | 'BD2B3V6SZ00' |'SOD323_1-85X1-25XA'| 'DIODE ZENER SMD BZT52-B3V6S(3.6V,5MA)'    | 'PJT'   | 'BZT52-B3V6S'     | 'EP(V1)'     | 'EP(V1)'  | 'IC'  | ''      | ''     | 'S5Z-WILLIAM' | 'PJT_BZT52-B3V6S.pdf'            | ''            | ''     | ''  | ''         | ''      | '20200504'
 'BZT52-B3V6S'     | 'SMLF'    | 'EMPTY'  | 'BD2B3V6SZ00'(!) = ''              | ''            | 'BD2B3V6SZ00' |'SOD323_1-85X1-25XA'| 'DIODE ZENER SMD BZT52-B3V6S(3.6V,5MA)'    | 'PJT'   | 'BZT52-B3V6S'     | 'EP(V1)'     | 'EP(V1)'  | 'IC'  | ''      | ''     | 'S5Z-WILLIAM' | 'PJT_BZT52-B3V6S.pdf'            | ''            | ''     | ''  | ''         | ''      | '20200504'
 'MM3Z12VT1G'      | 'SMLF'    | 'IC'     | 'BD12VT1GZ00'(!) = ''              | ''            | 'BD12VT1GZ00' |'SOD323XH'| 'DIODE ZENER MM3Z12VT1G (12V,SOD323)'      | 'ONS'   | 'MM3Z12VT1G'      | 'EP(V1)'     | ''        | 'IC'  | ''      | ''     | 'S8A-YC'      | 'ONS_MM3Z12VT1G.pdf'             | ''            | ''     | ''  | ''         | ''      | '20200610'
 'MM3Z12VT1G'      | 'SMLF'    | 'EMPTY'  | 'BD12VT1GZ00'(!) = ''              | ''            | 'BD12VT1GZ00' |'SOD323XH'| 'DIODE ZENER MM3Z12VT1G (12V,SOD323)'      | 'ONS'   | 'MM3Z12VT1G'      | 'EP(V1)'     | ''        | 'IC'  | ''      | ''     | 'S8A-YC'      | 'ONS_MM3Z12VT1G.pdf'             | ''            | ''     | ''  | ''         | ''      | '20200610'
 'PDZ12B'          | 'SMLF'    | 'IC'     | 'BDPDZ12BZ00'(!) = ''              | ''            | 'BDPDZ12BZ00' |'SOD323F_H44'| 'DIODE ZENER SMD PDZ12B(11.74V-12.24V)AEC' | 'NXE'   | 'PDZ12B'          | 'EU(V1)'     | ''        | 'IC'  | ''      | ''     | 'S8A-YC'      | 'NXE_PDZ12B.pdf'                 | ''            | ''     | ''  | ''         | ''      | '20200610'
 'PDZ12B'          | 'SMLF'    | 'EMPTY'  | 'BDPDZ12BZ00'(!) = ''              | ''            | 'BDPDZ12BZ00' |'SOD323F_H44'| 'DIODE ZENER SMD PDZ12B(11.74V-12.24V)AEC' | 'NXE'   | 'PDZ12B'          | 'EU(V1)'     | ''        | 'IC'  | ''      | ''     | 'S8A-YC'      | 'NXE_PDZ12B.pdf'                 | ''            | ''     | ''  | ''         | ''      | '20200610'
 'BZT52C24S'       | 'SMLF'    | 'IC'     | 'BD52C24SZ00'(!) = ''              | ''            | 'BD52C24SZ00' |'SOD323XI'| 'DIODE ZENER SMD BZT52C24S(24V 5MA)'       | 'DDS'   | 'BZT52C24S'       | 'EP(V1)'     | ''        | 'IC'  | ''      | ''     | 'P0A-STEVE'   | 'DDS_BZT52C24S.pdf'              | ''            | ''     | ''  | ''         | ''      | '20210311'
 'BZT52C24S'       | 'SMLF'    | 'EMPTY'  | 'BD52C24SZ00'(!) = ''              | ''            | 'BD52C24SZ00' |'SOD323XI'| 'DIODE ZENER SMD BZT52C24S(24V 5MA)'       | 'DDS'   | 'BZT52C24S'       | 'EP(V1)'     | ''        | 'IC'  | ''      | ''     | 'P0A-STEVE'   | 'DDS_BZT52C24S.pdf'              | ''            | ''     | ''  | ''         | ''      | '20210311'
 'MMSZ5230BT1G'    | 'SMLF'    | 'IC'     | 'BD5230BTZ00'(!) = ''              | ''            | 'BD5230BTZ00' |'SOD123XE'| 'DIODE ZENER MMSZ5230BT1G(4.7V,0.02A,0.5W' | 'ONS'   | 'MMSZ5230BT1G'    | 'EP(V1)'     | 'EP(V1)'  | 'IC'  | ''      | ''     | 'S8I-ANSON'   | 'ONS_MMSZ5230BT1G.pdf'           | ''            | ''     | ''  | ''         | ''      | '20210816'
 'MMSZ5230BT1G'    | 'SMLF'    | 'EMPTY'  | 'BD5230BTZ00'(!) = ''              | ''            | 'BD5230BTZ00' |'SOD123XE'| 'DIODE ZENER MMSZ5230BT1G(4.7V,0.02A,0.5W' | 'ONS'   | 'MMSZ5230BT1G'    | 'EP(V1)'     | 'EP(V1)'  | 'IC'  | ''      | ''     | 'S8I-ANSON'   | 'ONS_MMSZ5230BT1G.pdf'           | ''            | ''     | ''  | ''         | ''      | '20210816'
 'MMSZ5252BS-7-F'  | 'SMLF'    | 'IC'     | 'BD005252Z00'(!) = ''               | ''               | 'BD005252Z00' |'SOD323_1-7X1-3XA'| 'DIODE ZENER MMSZ5252BS-7-F(24V,SOD-323)'  | 'DDS'   | 'MMSZ5252BS-7-F'  | 'EP(V1)'     | ''        | 'IC'  | ''      | ''     | 'MF6-DANNY'   | 'DDS_MMSZ5252BS-7-F.pdf'         | ''            | ''     | ''  | ''         | ''      | '20230222'
 'MMSZ5252BS-7-F'  | 'SMLF'    | 'EMPTY'  | 'BD005252Z00'(!) = ''               | ''               | 'BD005252Z00' |'SOD323_1-7X1-3XA'| 'DIODE ZENER MMSZ5252BS-7-F(24V,SOD-323)'  | 'DDS'   | 'MMSZ5252BS-7-F'  | 'EP(V1)'     | ''        | 'IC'  | ''      | ''     | 'MF6-DANNY'   | 'DDS_MMSZ5252BS-7-F.pdf'         | ''            | ''     | ''  | ''         | ''      | '20230222'

END_PART

END.

